FILE_TYPE = CONNECTIVITY;
{Allegro Design Entry HDL 17.4-2019 S026 (4007227) 1/17/2022}
"PAGE_NUMBER" = 53;
0"NC";
1"P3E_CPU1_P4_RX_DN<3:0>";
2"P3E_CPU1_P4_RX_DP<3:0>";
3"P3E_CPU1_P4_TX_DN<3:0>";
4"P3E_CPU1_P4_TX_DP<3:0>";
5"P3E_CPU1_P5_TX_DN<0>";
6"P3E_CPU1_P5_TX_DP<0>";
7"P3E_CPU1_P5_TX_DN<1>";
8"P3E_CPU1_P5_TX_DP<1>";
9"P3E_CPU1_P5_RX_DP<1>";
10"P3E_CPU1_P5_RX_DN<0>";
11"P3E_CPU1_P5_RX_DN<1>";
12"P3E_CPU1_P5_RX_DP<0>";
13"WAFL_CPU0_TX0_CPU1_RX1_DN"$PHYS_NET_NAME"P3E_M2_0_SATA_RX_DP";
14"WAFL_CPU0_TX0_CPU1_RX1_DP";
15"WAFL_CPU1_TX1_CPU0_RX0_DN"$PHYS_NET_NAME"P3E_M2_0_SATA_RX_DP";
16"P3E_CPU1_P5_TX_C_DP<0>";
17"P3E_CPU1_P5_TX_C_DN<0>";
18"P3E_CPU1_P5_TX_C_DP<1>";
19"P3E_CPU1_P5_TX_C_DN<1>";
20"P3E_CPU1_P4_TX_DP<3>";
21"P3E_CPU1_P4_TX_DN<3>";
22"WAFL_CPU1_TX1_CPU0_RX0_DP";
23"P3E_CPU1_P4_TX_DN<0>";
24"P3E_CPU1_P4_TX_DN<1>";
25"P3E_CPU1_P4_TX_DP<0>";
26"P3E_CPU1_P4_TX_DP<1>";
27"P3E_CPU1_P4_TX_DP<2>";
28"P3E_CPU1_P4_TX_DN<2>";
29"P3E_CPU1_P4_RX_DP<0>";
30"P3E_CPU1_P4_RX_DP<2>";
31"P3E_CPU1_P4_RX_DP<1>";
32"P3E_CPU1_P4_RX_DN<0>";
33"P3E_CPU1_P4_RX_DN<1>";
34"P3E_CPU1_P4_RX_DP<3>";
35"P3E_CPU1_P4_RX_DN<2>";
36"P3E_CPU1_P4_RX_DN<3>";
%"TAP"
"6","(-6800,5275)","0","standard","I117";
;
CDS_LIB"standard"
BODY_TYPE"PLUMBING"
HDL_TAP"TRUE";
"B \NAC \NWC"1;
"S \NAC"
BN"3"36;
%"TAP"
"6","(-6800,5375)","0","standard","I118";
;
CDS_LIB"standard"
BODY_TYPE"PLUMBING"
HDL_TAP"TRUE";
"B \NAC \NWC"1;
"S \NAC"
BN"2"35;
%"TAP"
"6","(-6800,5475)","0","standard","I119";
;
CDS_LIB"standard"
BODY_TYPE"PLUMBING"
HDL_TAP"TRUE";
"B \NAC \NWC"1;
"S \NAC"
BN"1"33;
%"TAP"
"6","(-6650,5325)","0","standard","I120";
;
CDS_LIB"standard"
BODY_TYPE"PLUMBING"
HDL_TAP"TRUE";
"B \NAC \NWC"2;
"S \NAC"
BN"3"34;
%"TAP"
"6","(-6650,5425)","0","standard","I121";
;
CDS_LIB"standard"
BODY_TYPE"PLUMBING"
HDL_TAP"TRUE";
"B \NAC \NWC"2;
"S \NAC"
BN"2"30;
%"TAP"
"6","(-6650,5525)","0","standard","I122";
;
CDS_LIB"standard"
BODY_TYPE"PLUMBING"
HDL_TAP"TRUE";
"B \NAC \NWC"2;
"S \NAC"
BN"1"31;
%"TAP"
"6","(-6800,5575)","0","standard","I123";
;
CDS_LIB"standard"
BODY_TYPE"PLUMBING"
HDL_TAP"TRUE";
"B \NAC \NWC"1;
"S \NAC"
BN"0"32;
%"TAP"
"6","(-6650,5625)","0","standard","I124";
;
CDS_LIB"standard"
BODY_TYPE"PLUMBING"
HDL_TAP"TRUE";
"B \NAC \NWC"2;
"S \NAC"
BN"0"29;
%"TAP"
"6","(-3800,5425)","2","standard","I125";
;
ROOM"RISER1"
BOM_COST"IO_SLOT"
CDS_LIB"standard"
BODY_TYPE"PLUMBING"
HDL_TAP"TRUE";
"B \NAC \NWC"4;
"S \NAC"
BN"2"27;
%"TAP"
"6","(-3800,5325)","2","standard","I126";
;
ROOM"RISER1"
BOM_COST"IO_SLOT"
CDS_LIB"standard"
BODY_TYPE"PLUMBING"
HDL_TAP"TRUE";
"B \NAC \NWC"4;
"S \NAC"
BN"3"20;
%"TAP"
"6","(-3800,5525)","2","standard","I127";
;
ROOM"RISER1"
BOM_COST"IO_SLOT"
CDS_LIB"standard"
BODY_TYPE"PLUMBING"
HDL_TAP"TRUE";
"B \NAC \NWC"4;
"S \NAC"
BN"1"26;
%"TAP"
"6","(-3800,5625)","2","standard","I128";
;
ROOM"RISER1"
BOM_COST"IO_SLOT"
CDS_LIB"standard"
BODY_TYPE"PLUMBING"
HDL_TAP"TRUE";
"B \NAC \NWC"4;
"S \NAC"
BN"0"25;
%"TAP"
"6","(-3650,5275)","2","standard","I129";
;
ROOM"RISER1"
BOM_COST"IO_SLOT"
CDS_LIB"standard"
BODY_TYPE"PLUMBING"
HDL_TAP"TRUE";
"B \NAC \NWC"3;
"S \NAC"
BN"3"21;
%"TAP"
"6","(-3650,5475)","2","standard","I130";
;
ROOM"RISER1"
BOM_COST"IO_SLOT"
CDS_LIB"standard"
BODY_TYPE"PLUMBING"
HDL_TAP"TRUE";
"B \NAC \NWC"3;
"S \NAC"
BN"1"24;
%"TAP"
"6","(-3650,5375)","2","standard","I131";
;
ROOM"RISER1"
BOM_COST"IO_SLOT"
CDS_LIB"standard"
BODY_TYPE"PLUMBING"
HDL_TAP"TRUE";
"B \NAC \NWC"3;
"S \NAC"
BN"2"28;
%"Q_CAP_DIFFBUS"
"2","(-3050,4775)","2","pure_quanta","I132";
;
LOCATION"C2073"
$SEC"1"
CDS_SEC"1"
VALUE"DIFF BUS_0.22UF"
CDS_LIB"pure_quanta"
CDS_LMAN_SYM_OUTLINE"-25,50,25,-50"
VOLTAGE"6.3V"
TOLERANCE"20%"
PACK_TYPE"C0201"
MATERIAL"X6S"
PIN_NAMES_ROTATE"TRUE"
PART_NUMBER"SP_CH4221MEE01";
"2"
$PN"2"8;
"1"
$PN"1"18;
%"Q_CAP_DIFFBUS"
"2","(-3050,4725)","2","pure_quanta","I133";
;
LOCATION"C2074"
$SEC"1"
CDS_SEC"1"
VOLTAGE"6.3V"
TOLERANCE"20%"
VALUE"DIFF BUS_0.22UF"
MATERIAL"X6S"
PACK_TYPE"C0201"
CDS_LIB"pure_quanta"
CDS_LMAN_SYM_OUTLINE"-25,50,25,-50"
PIN_NAMES_ROTATE"TRUE"
PART_NUMBER"SP_CH4221MEE01";
"2"
$PN"2"7;
"1"
$PN"1"19;
%"Q_CAP_DIFFBUS"
"2","(-3050,4825)","2","pure_quanta","I134";
;
LOCATION"C2076"
$SEC"1"
CDS_SEC"1"
VALUE"DIFF BUS_0.22UF"
CDS_LIB"pure_quanta"
CDS_LMAN_SYM_OUTLINE"-25,50,25,-50"
PIN_NAMES_ROTATE"TRUE"
MATERIAL"X6S"
PACK_TYPE"C0201"
TOLERANCE"20%"
VOLTAGE"6.3V"
PART_NUMBER"SP_CH4221MEE01";
"2"
$PN"2"5;
"1"
$PN"1"17;
%"Q_CAP_DIFFBUS"
"2","(-3050,4875)","2","pure_quanta","I135";
;
LOCATION"C2075"
$SEC"1"
CDS_SEC"1"
VALUE"DIFF BUS_0.22UF"
CDS_LIB"pure_quanta"
CDS_LMAN_SYM_OUTLINE"-25,50,25,-50"
VOLTAGE"6.3V"
TOLERANCE"20%"
PACK_TYPE"C0201"
MATERIAL"X6S"
PIN_NAMES_ROTATE"TRUE"
PART_NUMBER"SP_CH4221MEE01";
"2"
$PN"2"6;
"1"
$PN"1"16;
%"TAP"
"6","(-3650,5575)","2","standard","I138";
;
ROOM"RISER1"
BOM_COST"IO_SLOT"
CDS_LIB"standard"
BODY_TYPE"PLUMBING"
HDL_TAP"TRUE";
"B \NAC \NWC"3;
"S \NAC"
BN"0"23;
%"GENOA_SP5"
"19","(-5175,5225)","0","pure_quanta","I145";
;
LOCATION"U26"
$SEC"19"
CDS_SEC"19"
MATERIAL"IO"
VALUE"SOCKET6096_13568-001"
PART_TYPE"SMLF"
CDS_LIB"pure_quanta"
CDS_LMAN_SYM_OUTLINE"-800,600,800,-600"
NEEDS_NO_SIZE"TRUE"
PART_NUMBER"DGA^6000030";
"WAFL_TXP1||P5_TXP1"
$PN"C47"22;
"WAFL_TXN1||P5_TXN1"
$PN"C48"15;
"WAFL_TXP0||P5_TXP0"
$PN"C50"0;
"WAFL_TXN0||P5_TXN0"
$PN"C51"0;
"WAFL_RXP1||P5_RXP1"
$PN"E46"14;
"WAFL_RXN1||P5_RXN1"
$PN"E47"13;
"WAFL_RXP0||P5_RXP0"
$PN"E49"0;
"WAFL_RXN0||P5_RXN0"
$PN"E50"0;
"P4_RXN1"
$PN"DG50"33;
"P4_RXN0"
$PN"DG53"32;
"P4_RXP1"
$PN"DG51"31;
"P4_TXN1"
$PN"DE49"24;
"P4_RXP0"
$PN"DG54"29;
"P4_TXN0"
$PN"DE52"23;
"P4_TXP1"
$PN"DE50"26;
"P4_TXP0"
$PN"DE53"25;
"P5_TXP3"
$PN"C41"8;
"P5_TXP2"
$PN"C44"6;
"P5_TXN3"
$PN"C42"7;
"P5_TXN2"
$PN"C45"5;
"P5_RXP3"
$PN"E40"11;
"P5_RXP2"
$PN"E43"10;
"P5_RXN3"
$PN"E41"9;
"P5_RXN2"
$PN"E44"12;
"P4_TXP3"
$PN"DE44"20;
"P4_TXP2"
$PN"DE47"27;
"P4_TXN3"
$PN"DE43"21;
"P4_TXN2"
$PN"DE46"28;
"P4_RXP3"
$PN"DG45"34;
"P4_RXP2"
$PN"DG48"30;
"P4_RXN3"
$PN"DG44"36;
"P4_RXN2"
$PN"DG47"35;
END.
